(kicad_pcb
	(version 20260206)
	(generator "pcbnew")
	(generator_version "10.0")
	(general
		(thickness 1.6)
		(legacy_teardrops no)
	)
	(paper "A4")
	(title_block
		(title "Bryce Canyon_IOM_M2_16342-2_OCP.brd")
		(comment 1 "Bryce Canyon / footprints 65-68 of 1146")
	)
	(layers
		(0 "F.Cu" signal "TOP")
		(4 "In1.Cu" signal "L2GND")
		(6 "In2.Cu" signal "L3")
		(8 "In3.Cu" signal "L4VCC")
		(10 "In4.Cu" signal "L5VCC")
		(12 "In5.Cu" signal "L6")
		(14 "In6.Cu" signal "L7GND")
		(2 "B.Cu" signal "BOTTOM")
		(9 "F.Adhes" user "F.Adhesive")
		(11 "B.Adhes" user "B.Adhesive")
		(13 "F.Paste" user "Package Geometry/Pastemask Top")
		(15 "B.Paste" user "Package Geometry/Pastemask Bottom")
		(5 "F.SilkS" user "Ref Des/Silkscreen Top")
		(7 "B.SilkS" user "Ref Des/Silkscreen Bottom")
		(1 "F.Mask" user "Board Geometry/Soldermask Top")
		(3 "B.Mask" user "Board Geometry/Soldermask Bottom")
		(17 "Dwgs.User" user "User.Drawings")
		(19 "Cmts.User" user "User.Comments")
		(21 "Eco1.User" user "User.Eco1")
		(23 "Eco2.User" user "User.Eco2")
		(25 "Edge.Cuts" user "Board Geometry/Outline")
		(27 "Margin" user)
		(31 "F.CrtYd" user "Package Geometry/Place Bound Top")
		(29 "B.CrtYd" user "Package Geometry/Place Bound Bottom")
		(35 "F.Fab" user "Ref Des/Assembly Top")
		(33 "B.Fab" user "Ref Des/Assembly Bottom")
	)
	(footprint ""
		(layer "F.Cu")
		(at 77.283818 -80.554068 90)
		(property "Reference" "VIA4"
			(at 0 0 90)
			(layer "F.SilkS")
			(hide yes)
			(effects
				(font
					(size 1.27 1.27)
				)
			)
		)
		(property "Value" "85OHM-8L-1D6MM-L16L18-GP"
			(at 4.064 0.6096 90)
			(unlocked yes)
			(layer "F.Fab")
			(hide yes)
			(effects
				(font
					(size 1.016 1.016)
					(thickness 0.1524)
				)
			)
		)
		(property "Device Type" "VIA-PCIE-4P-368076"
			(at 4.064 -0.9144 90)
			(unlocked yes)
			(layer "F.Fab")
			(hide yes)
			(effects
				(font
					(size 1.016 1.016)
					(thickness 0.1524)
				)
			)
		)
		(duplicate_pad_numbers_are_jumpers no)
		(fp_rect
			(start -1.8415 0.381)
			(end 1.8415 -0.381)
			(stroke
				(width 0)
				(type default)
			)
			(fill no)
			(layer "F.CrtYd")
		)
		(fp_rect
			(start -1.8415 0.381)
			(end 1.8415 -0.381)
			(stroke
				(width 0)
				(type default)
			)
			(fill no)
			(layer "F.Fab")
		)
		(pad "1" thru_hole circle
			(at -1.4605 0 90)
			(size 0.508 0.508)
			(drill 0.254)
			(layers "*.Cu" "*.Mask")
			(remove_unused_layers no)
			(net "GND")
			(clearance 0.127)
			(thermal_gap 0.127)
		)
		(pad "2" thru_hole circle
			(at -0.4445 0 90)
			(size 0.508 0.508)
			(drill 0.254)
			(layers "*.Cu" "*.Mask")
			(remove_unused_layers no)
			(net "PCIE_COMP_TO_IOM_19_DP")
			(clearance 0.127)
			(thermal_gap 0.127)
		)
		(pad "3" thru_hole circle
			(at 0.4445 0 90)
			(size 0.508 0.508)
			(drill 0.254)
			(layers "*.Cu" "*.Mask")
			(remove_unused_layers no)
			(net "PCIE_COMP_TO_IOM_19_DN")
			(clearance 0.127)
			(thermal_gap 0.127)
		)
		(pad "4" thru_hole circle
			(at 1.4605 0 90)
			(size 0.508 0.508)
			(drill 0.254)
			(layers "*.Cu" "*.Mask")
			(remove_unused_layers no)
			(net "GND")
			(clearance 0.127)
			(thermal_gap 0.127)
		)
	)
	(footprint ""
		(layer "F.Cu")
		(at 69.5452 -175.1584 180)
		(property "Reference" "U31"
			(at 0 0 180)
			(layer "F.SilkS")
			(hide yes)
			(effects
				(font
					(size 1.27 1.27)
				)
			)
		)
		(property "Value" "SN74LVC1G08DCKR-GP"
			(at -2.3368 -8.6868 180)
			(unlocked yes)
			(layer "F.Fab")
			(hide yes)
			(effects
				(font
					(size 1.016 1.016)
					(thickness 0.1524)
				)
			)
		)
		(property "Device Type" "SC70-5H44"
			(at -2.3114 -10.414 180)
			(unlocked yes)
			(layer "F.Fab")
			(hide yes)
			(effects
				(font
					(size 1.016 1.016)
					(thickness 0.1524)
				)
			)
		)
		(duplicate_pad_numbers_are_jumpers no)
		(fp_line
			(start 1.3843 -1.8034)
			(end 1.3843 -1.1176)
			(stroke
				(width 0.3302)
				(type default)
			)
			(layer "F.SilkS")
		)
		(fp_line
			(start 1.27 1.7018)
			(end -1.27 1.7018)
			(stroke
				(width 0.1524)
				(type default)
			)
			(layer "F.SilkS")
		)
		(fp_line
			(start 1.27 -1.7018)
			(end 1.27 1.7018)
			(stroke
				(width 0.1524)
				(type default)
			)
			(layer "F.SilkS")
		)
		(fp_line
			(start 0.6604 -1.8034)
			(end 1.3843 -1.8034)
			(stroke
				(width 0.3302)
				(type default)
			)
			(layer "F.SilkS")
		)
		(fp_line
			(start -1.27 1.7018)
			(end -1.27 -1.7018)
			(stroke
				(width 0.1524)
				(type default)
			)
			(layer "F.SilkS")
		)
		(fp_line
			(start -1.27 -1.7018)
			(end 1.27 -1.7018)
			(stroke
				(width 0.1524)
				(type default)
			)
			(layer "F.SilkS")
		)
		(fp_rect
			(start -1.524 1.9558)
			(end 1.524 -1.9558)
			(stroke
				(width 0)
				(type default)
			)
			(fill no)
			(layer "F.CrtYd")
		)
		(fp_poly
			(pts
				(xy -1.524 -1.9558) (xy 1.524 -1.9558) (xy 1.524 1.9558) (xy -1.524 1.9558)
			)
			(stroke
				(width 0)
				(type default)
			)
			(fill no)
			(layer "F.Fab")
		)
		(pad "1" smd rect
			(at 0.65024 -0.8255 180)
			(size 0.4064 1.2192)
			(layers "F.Cu" "F.Mask" "F.Paste")
			(net "COMP_TO_BMC_RESET_N_OUT")
		)
		(pad "2" smd rect
			(at 0 -0.8255 180)
			(size 0.4064 1.2192)
			(layers "F.Cu" "F.Mask" "F.Paste")
			(net "BMC_TPM_RST_N")
		)
		(pad "3" smd rect
			(at -0.65024 -0.8255 180)
			(size 0.4064 1.2192)
			(layers "F.Cu" "F.Mask" "F.Paste")
			(net "GND")
		)
		(pad "4" smd rect
			(at -0.65024 0.8255 180)
			(size 0.4064 1.2192)
			(layers "F.Cu" "F.Mask" "F.Paste")
			(net "RST_BMC_EXTRST_N_1")
		)
		(pad "5" smd rect
			(at 0.65024 0.8255 180)
			(size 0.4064 1.2192)
			(layers "F.Cu" "F.Mask" "F.Paste")
			(net "P3V3_STBY")
		)
	)
	(footprint ""
		(layer "F.Cu")
		(at 60.656978 -166.845234 180)
		(property "Reference" "R75"
			(at 0 0 180)
			(layer "F.SilkS")
			(hide yes)
			(effects
				(font
					(size 1.27 1.27)
				)
			)
		)
		(property "Value" "0R2J-2-GP"
			(at 0.064008 -3.993896 180)
			(unlocked yes)
			(layer "F.Fab")
			(hide yes)
			(effects
				(font
					(size 1.016 1.016)
					(thickness 0.1524)
				)
			)
		)
		(property "Device Type" "R402H16"
			(at 0.064008 -5.517896 180)
			(unlocked yes)
			(layer "F.Fab")
			(hide yes)
			(effects
				(font
					(size 1.016 1.016)
					(thickness 0.1524)
				)
			)
		)
		(duplicate_pad_numbers_are_jumpers no)
		(fp_line
			(start 0.508 -0.9398)
			(end -0.508 -0.9398)
			(stroke
				(width 0.1524)
				(type default)
			)
			(layer "F.SilkS")
		)
		(fp_line
			(start -0.508 -0.9398)
			(end -0.508 0.9398)
			(stroke
				(width 0.1524)
				(type default)
			)
			(layer "F.SilkS")
		)
		(fp_rect
			(start -0.508 0.9398)
			(end 0.508 -0.9398)
			(stroke
				(width 0)
				(type default)
			)
			(fill no)
			(layer "F.CrtYd")
		)
		(fp_rect
			(start -0.508 0.9398)
			(end 0.508 -0.9398)
			(stroke
				(width 0)
				(type default)
			)
			(fill no)
			(layer "F.Fab")
		)
		(pad "1" smd custom
			(at 0 -0.4445 180)
			(size 0.1397 0.1397)
			(layers "F.Cu" "F.Mask" "F.Paste")
			(net "BMC_SELF_HW_RST_D")
			(options
				(clearance outline)
				(anchor circle)
			)
			(primitives
				(gr_poly
					(pts
						(arc
							(start -0.1778 -0.2794)
							(mid -0.249642 -0.249642)
							(end -0.2794 -0.1778)
						)
						(arc
							(start -0.2794 0.1778)
							(mid -0.249642 0.249642)
							(end -0.1778 0.2794)
						)
						(arc
							(start 0.1778 0.2794)
							(mid 0.249642 0.249642)
							(end 0.2794 0.1778)
						)
						(arc
							(start 0.2794 -0.1778)
							(mid 0.249642 -0.249642)
							(end 0.1778 -0.2794)
						)
					)
					(width 0)
					(fill yes)
				)
			)
		)
		(pad "2" smd custom
			(at 0 0.4445 180)
			(size 0.1397 0.1397)
			(layers "F.Cu" "F.Mask" "F.Paste")
			(net "FM_TPM_PRSNT_RST_N")
			(options
				(clearance outline)
				(anchor circle)
			)
			(primitives
				(gr_poly
					(pts
						(arc
							(start -0.1778 -0.2794)
							(mid -0.249642 -0.249642)
							(end -0.2794 -0.1778)
						)
						(arc
							(start -0.2794 0.1778)
							(mid -0.249642 0.249642)
							(end -0.1778 0.2794)
						)
						(arc
							(start 0.1778 0.2794)
							(mid 0.249642 0.249642)
							(end 0.2794 0.1778)
						)
						(arc
							(start 0.2794 -0.1778)
							(mid 0.249642 -0.249642)
							(end 0.1778 -0.2794)
						)
					)
					(width 0)
					(fill yes)
				)
			)
		)
	)
	(footprint ""
		(layer "F.Cu")
		(at 222.293688 -28.229052 -90)
		(property "Reference" "C167"
			(at 0 0 270)
			(layer "F.SilkS")
			(hide yes)
			(effects
				(font
					(size 1.27 1.27)
				)
			)
		)
		(property "Value" "ST100U16VDM-3-GP"
			(at 0 -9.6012 270)
			(unlocked yes)
			(layer "F.Fab")
			(hide yes)
			(effects
				(font
					(size 1.016 1.016)
					(thickness 0.1524)
				)
			)
		)
		(property "Device Type" "CT7343H79"
			(at 0 -11.1252 270)
			(unlocked yes)
			(layer "F.Fab")
			(hide yes)
			(effects
				(font
					(size 1.016 1.016)
					(thickness 0.1524)
				)
			)
		)
		(duplicate_pad_numbers_are_jumpers no)
		(fp_line
			(start -2.286 4.8768)
			(end -2.286 2.032)
			(stroke
				(width 0.1524)
				(type default)
			)
			(layer "F.SilkS")
		)
		(fp_line
			(start 2.286 4.8768)
			(end -2.286 4.8768)
			(stroke
				(width 0.1524)
				(type default)
			)
			(layer "F.SilkS")
		)
		(fp_line
			(start 2.286 2.032)
			(end 2.286 4.8768)
			(stroke
				(width 0.1524)
				(type default)
			)
			(layer "F.SilkS")
		)
		(fp_line
			(start 2.286 -2.032)
			(end 2.286 -4.8768)
			(stroke
				(width 0.1524)
				(type default)
			)
			(layer "F.SilkS")
		)
		(fp_line
			(start 2.1082 -4.699)
			(end -2.1082 -4.699)
			(stroke
				(width 0.508)
				(type default)
			)
			(layer "F.SilkS")
		)
		(fp_line
			(start -2.286 -4.8768)
			(end -2.286 -2.032)
			(stroke
				(width 0.1524)
				(type default)
			)
			(layer "F.SilkS")
		)
		(fp_line
			(start 2.286 -4.8768)
			(end -2.286 -4.8768)
			(stroke
				(width 0.1524)
				(type default)
			)
			(layer "F.SilkS")
		)
		(fp_rect
			(start -2.1463 3.6449)
			(end 2.1463 -3.6449)
			(stroke
				(width 0)
				(type default)
			)
			(fill no)
			(layer "F.CrtYd")
		)
		(fp_poly
			(pts
				(xy -2.54 4.953) (xy -2.54 4.2926) (xy -3.81 4.2926) (xy -3.81 -4.2926) (xy -2.54 -4.2926) (xy -2.54 -4.953)
				(xy 2.54 -4.953) (xy 2.54 -4.2926) (xy 3.81 -4.2926) (xy 3.81 -1.6256) (xy 2.1463 -1.6256) (xy 2.1463 -3.6449)
				(xy -2.1463 -3.6449) (xy -2.1463 3.6449) (xy 2.1463 3.6449) (xy 2.1463 -1.6129) (xy 3.81 -1.6129)
				(xy 3.81 4.2926) (xy 2.54 4.2926) (xy 2.54 4.953)
			)
			(stroke
				(width 0)
				(type default)
			)
			(fill no)
			(layer "F.CrtYd")
		)
		(fp_rect
			(start -2.54 4.953)
			(end 2.54 -4.953)
			(stroke
				(width 0)
				(type default)
			)
			(fill no)
			(layer "F.Fab")
		)
		(fp_rect
			(start -3.81 4.2926)
			(end -2.54 -4.2926)
			(stroke
				(width 0)
				(type default)
			)
			(fill no)
			(layer "F.Fab")
		)
		(fp_rect
			(start 2.54 4.2926)
			(end 3.81 -4.2926)
			(stroke
				(width 0)
				(type default)
			)
			(fill no)
			(layer "F.Fab")
		)
		(pad "1" smd rect
			(at 0 -3.1496 270)
			(size 2.413 2.286)
			(layers "F.Cu" "F.Mask" "F.Paste")
			(net "P5V_STBY")
		)
		(pad "2" smd rect
			(at 0 3.1496 270)
			(size 2.413 2.286)
			(layers "F.Cu" "F.Mask" "F.Paste")
			(net "GND")
		)
		(zone
			(layer "F.Cu")
			(hatch none 0.5)
			(connect_pads
				(clearance 0)
			)
			(min_thickness 0.25)
			(keepout
				(tracks allowed)
				(vias not_allowed)
				(pads allowed)
				(copperpour not_allowed)
				(footprints allowed)
			)
			(placement
				(enabled no)
				(sheetname "")
			)
			(fill
				(thermal_gap 0.5)
				(thermal_bridge_width 0.5)
				(island_removal_mode 0)
			)
			(polygon
				(pts
					(xy 217.696288 -29.740352) (xy 217.696288 -26.717752) (xy 220.591888 -26.717752) (xy 220.922088 -26.717752)
					(xy 220.922088 -29.740352) (xy 220.591888 -29.740352)
				)
			)
		)
		(zone
			(layer "F.Cu")
			(hatch none 0.5)
			(connect_pads
				(clearance 0)
			)
			(min_thickness 0.25)
			(keepout
				(tracks allowed)
				(vias not_allowed)
				(pads allowed)
				(copperpour not_allowed)
				(footprints allowed)
			)
			(placement
				(enabled no)
				(sheetname "")
			)
			(fill
				(thermal_gap 0.5)
				(thermal_bridge_width 0.5)
				(island_removal_mode 0)
			)
			(polygon
				(pts
					(xy 223.982788 -26.717752) (xy 226.891088 -26.717752) (xy 226.891088 -29.740352) (xy 223.995488 -29.740352)
					(xy 223.665288 -29.740352) (xy 223.665288 -26.717752)
				)
			)
		)
	)
)
